# S9S_MB_2U (Grand Teton) — schematic netlist excerpt (pin names and nets, part order shuffled) for the footprints in the layout excerpt that follows; sources: Cadence DE-HDL packaged netlist, KiCad conversion of 03242023_DA0F0TMBIJ0_F0T_Motherboard_J_brd_V01_OCP.brd

R4497  Q_RES  33.2 1% CHIP  pkg 0402LF  page 237 : A = SMB_HOST_CLK_BUF_ISO_3V3AUX_SDA ; B = SMB_HOST_DB2000_3V3AUX_SDA
R2219  Q_RES  26.7K 1% CHIP  pkg 0402LF  page 306 : A = P12V_AUX ; B = A_P12V_STBY_ADR_TRIGGER

(kicad_pcb
	(version 20260206)
	(generator "pcbnew")
	(generator_version "10.0")
	(general
		(thickness 1.6)
		(legacy_teardrops no)
	)
	(paper "A4")
	(title_block
		(title "03242023_DA0F0TMBIJ0_F0T_Motherboard_J_brd_V01_OCP.brd")
		(comment 1 "Grand Teton / footprints 859-860 of 6105")
	)
	(layers
		(0 "F.Cu" signal "TOP")
		(4 "In1.Cu" signal "GND")
		(6 "In2.Cu" signal "IN1")
		(8 "In3.Cu" signal "GND1")
		(10 "In4.Cu" signal "IN2")
		(12 "In5.Cu" signal "GND2")
		(14 "In6.Cu" signal "IN3")
		(16 "In7.Cu" signal "GND3")
		(18 "In8.Cu" signal "VCC")
		(20 "In9.Cu" signal "VCC1")
		(22 "In10.Cu" signal "GND4")
		(24 "In11.Cu" signal "IN4")
		(26 "In12.Cu" signal "GND5")
		(28 "In13.Cu" signal "IN5")
		(30 "In14.Cu" signal "GND6")
		(32 "In15.Cu" signal "IN6")
		(34 "In16.Cu" signal "GND7")
		(2 "B.Cu" signal "BOTTOM")
		(9 "F.Adhes" user "F.Adhesive")
		(11 "B.Adhes" user "B.Adhesive")
		(13 "F.Paste" user "Package Geometry/Pastemask Top")
		(15 "B.Paste" user "Package Geometry/Pastemask Bottom")
		(5 "F.SilkS" user "Ref Des/Silkscreen Top")
		(7 "B.SilkS" user "Ref Des/Silkscreen Bottom")
		(1 "F.Mask" user "Board Geometry/Soldermask Top")
		(3 "B.Mask" user "Board Geometry/Soldermask Bottom")
		(17 "Dwgs.User" user "User.Drawings")
		(19 "Cmts.User" user "User.Comments")
		(21 "Eco1.User" user "User.Eco1")
		(23 "Eco2.User" user "User.Eco2")
		(25 "Edge.Cuts" user "Board Geometry/Outline")
		(27 "Margin" user)
		(31 "F.CrtYd" user "Package Geometry/Place Bound Top")
		(29 "B.CrtYd" user "Package Geometry/Place Bound Bottom")
		(35 "F.Fab" user "Ref Des/Assembly Top")
		(33 "B.Fab" user "Ref Des/Assembly Bottom")
	)
	(footprint ""
		(layer "F.Cu")
		(at 210.560412 -98.809048)
		(property "Reference" "R2219"
			(at 0 0 0)
			(layer "F.SilkS")
			(hide yes)
			(effects
				(font
					(size 1.27 1.27)
				)
			)
		)
		(property "Value" ""
			(at 0 0 0)
			(layer "F.Fab")
			(effects
				(font
					(size 1.27 1.27)
				)
			)
		)
		(duplicate_pad_numbers_are_jumpers no)
		(fp_line
			(start -0.7874 -0.4064)
			(end 0.7874 -0.4064)
			(stroke
				(width 0.1524)
				(type default)
			)
			(layer "F.SilkS")
		)
		(fp_line
			(start -0.7874 0.4064)
			(end -0.7874 -0.4064)
			(stroke
				(width 0.1524)
				(type default)
			)
			(layer "F.SilkS")
		)
		(fp_line
			(start 0.7874 -0.4064)
			(end 0.7874 0.4064)
			(stroke
				(width 0.1524)
				(type default)
			)
			(layer "F.SilkS")
		)
		(fp_line
			(start 0.7874 0.4064)
			(end -0.7874 0.4064)
			(stroke
				(width 0.1524)
				(type default)
			)
			(layer "F.SilkS")
		)
		(fp_line
			(start -0.67945 -0.305054)
			(end -0.12065 -0.305054)
			(stroke
				(width 0.1)
				(type default)
			)
			(layer "F.Fab")
		)
		(fp_line
			(start -0.67945 0.3048)
			(end -0.67945 -0.305054)
			(stroke
				(width 0.1)
				(type default)
			)
			(layer "F.Fab")
		)
		(fp_line
			(start -0.12065 -0.305054)
			(end -0.12065 -0.2794)
			(stroke
				(width 0.1)
				(type default)
			)
			(layer "F.Fab")
		)
		(fp_line
			(start -0.12065 -0.2794)
			(end 0.12065 -0.2794)
			(stroke
				(width 0.1)
				(type default)
			)
			(layer "F.Fab")
		)
		(fp_line
			(start -0.12065 0.2794)
			(end -0.12065 0.3048)
			(stroke
				(width 0.1)
				(type default)
			)
			(layer "F.Fab")
		)
		(fp_line
			(start -0.12065 0.3048)
			(end -0.67945 0.3048)
			(stroke
				(width 0.1)
				(type default)
			)
			(layer "F.Fab")
		)
		(fp_line
			(start 0.120396 0.2794)
			(end -0.12065 0.2794)
			(stroke
				(width 0.1)
				(type default)
			)
			(layer "F.Fab")
		)
		(fp_line
			(start 0.120396 0.3048)
			(end 0.120396 0.2794)
			(stroke
				(width 0.1)
				(type default)
			)
			(layer "F.Fab")
		)
		(fp_line
			(start 0.12065 -0.3048)
			(end 0.67945 -0.3048)
			(stroke
				(width 0.1)
				(type default)
			)
			(layer "F.Fab")
		)
		(fp_line
			(start 0.12065 -0.2794)
			(end 0.12065 -0.3048)
			(stroke
				(width 0.1)
				(type default)
			)
			(layer "F.Fab")
		)
		(fp_line
			(start 0.67945 -0.3048)
			(end 0.67945 0.3048)
			(stroke
				(width 0.1)
				(type default)
			)
			(layer "F.Fab")
		)
		(fp_line
			(start 0.67945 0.3048)
			(end 0.120396 0.3048)
			(stroke
				(width 0.1)
				(type default)
			)
			(layer "F.Fab")
		)
		(pad "1" smd circle
			(at -0.40005 0)
			(size 0 0)
			(layers "F.Cu" "F.Mask" "F.Paste")
			(net "P12V_AUX")
		)
		(pad "2" smd circle
			(at 0.40005 0)
			(size 0 0)
			(layers "F.Cu" "F.Mask" "F.Paste")
			(net "A_P12V_STBY_ADR_TRIGGER")
		)
	)
	(footprint ""
		(layer "F.Cu")
		(at 261.436612 -133.001512 180)
		(property "Reference" "R4497"
			(at 0 0 180)
			(layer "F.SilkS")
			(hide yes)
			(effects
				(font
					(size 1.27 1.27)
				)
			)
		)
		(property "Value" ""
			(at 0 0 180)
			(layer "F.Fab")
			(effects
				(font
					(size 1.27 1.27)
				)
			)
		)
		(duplicate_pad_numbers_are_jumpers no)
		(fp_line
			(start 0.7874 0.4064)
			(end -0.7874 0.4064)
			(stroke
				(width 0.1524)
				(type default)
			)
			(layer "F.SilkS")
		)
		(fp_line
			(start 0.7874 -0.4064)
			(end 0.7874 0.4064)
			(stroke
				(width 0.1524)
				(type default)
			)
			(layer "F.SilkS")
		)
		(fp_line
			(start -0.7874 0.4064)
			(end -0.7874 -0.4064)
			(stroke
				(width 0.1524)
				(type default)
			)
			(layer "F.SilkS")
		)
		(fp_line
			(start -0.7874 -0.4064)
			(end 0.7874 -0.4064)
			(stroke
				(width 0.1524)
				(type default)
			)
			(layer "F.SilkS")
		)
		(fp_line
			(start 0.67945 0.3048)
			(end 0.120396 0.3048)
			(stroke
				(width 0.1)
				(type default)
			)
			(layer "F.Fab")
		)
		(fp_line
			(start 0.67945 -0.3048)
			(end 0.67945 0.3048)
			(stroke
				(width 0.1)
				(type default)
			)
			(layer "F.Fab")
		)
		(fp_line
			(start 0.12065 -0.2794)
			(end 0.12065 -0.3048)
			(stroke
				(width 0.1)
				(type default)
			)
			(layer "F.Fab")
		)
		(fp_line
			(start 0.12065 -0.3048)
			(end 0.67945 -0.3048)
			(stroke
				(width 0.1)
				(type default)
			)
			(layer "F.Fab")
		)
		(fp_line
			(start 0.120396 0.3048)
			(end 0.120396 0.2794)
			(stroke
				(width 0.1)
				(type default)
			)
			(layer "F.Fab")
		)
		(fp_line
			(start 0.120396 0.2794)
			(end -0.12065 0.2794)
			(stroke
				(width 0.1)
				(type default)
			)
			(layer "F.Fab")
		)
		(fp_line
			(start -0.12065 0.3048)
			(end -0.67945 0.3048)
			(stroke
				(width 0.1)
				(type default)
			)
			(layer "F.Fab")
		)
		(fp_line
			(start -0.12065 0.2794)
			(end -0.12065 0.3048)
			(stroke
				(width 0.1)
				(type default)
			)
			(layer "F.Fab")
		)
		(fp_line
			(start -0.12065 -0.2794)
			(end 0.12065 -0.2794)
			(stroke
				(width 0.1)
				(type default)
			)
			(layer "F.Fab")
		)
		(fp_line
			(start -0.12065 -0.305054)
			(end -0.12065 -0.2794)
			(stroke
				(width 0.1)
				(type default)
			)
			(layer "F.Fab")
		)
		(fp_line
			(start -0.67945 0.3048)
			(end -0.67945 -0.305054)
			(stroke
				(width 0.1)
				(type default)
			)
			(layer "F.Fab")
		)
		(fp_line
			(start -0.67945 -0.305054)
			(end -0.12065 -0.305054)
			(stroke
				(width 0.1)
				(type default)
			)
			(layer "F.Fab")
		)
		(pad "1" smd circle
			(at -0.40005 0 180)
			(size 0 0)
			(layers "F.Cu" "F.Mask" "F.Paste")
			(net "SMB_HOST_CLK_BUF_ISO_3V3AUX_SDA")
		)
		(pad "2" smd circle
			(at 0.40005 0 180)
			(size 0 0)
			(layers "F.Cu" "F.Mask" "F.Paste")
			(net "SMB_HOST_DB2000_3V3AUX_SDA")
		)
	)
)
